# T6G (Grand Teton) — schematic netlist excerpt (pin names and nets, part order shuffled) for the footprints in the layout excerpt that follows; sources: Cadence DE-HDL packaged netlist, KiCad conversion of 04192023_DAF0TMB3IC0_F0TG_MB_C_brd_V02_OCP.brd

J37  SCONN288_DDR506112002KQ  IO  pkg DDR288S_1-1VXC  page 109
  VIN_BULK0  = P12V_MEM_CPU1
  RFU0  = NC
  VIN_MGMT  = P3V3_AUX
  HSCL  = I3C_SPD_DDRL_CPU1_SCL
  HSDA  = I3C_SPD_DDRL_CPU1_SDA
  VSS0  = GND
  DQ0_A  = M_L_CPU1_SA_DQ<0>
  VSS1  = GND
  DQ1_A  = M_L_CPU1_SA_DQ<1>
  VSS2  = GND
  DQS0_A_T  = M_L_CPU1_SA_DQS_DP<0>
  DQS0_A_C  = M_L_CPU1_SA_DQS_DN<0>
  VSS3  = GND
  DQ4_A  = M_L_CPU1_SA_DQ<4>
  VSS4  = GND
  DQ5_A  = M_L_CPU1_SA_DQ<5>
  VSS5  = GND
  DQ8_A  = M_L_CPU1_SA_DQ<8>
  VSS6  = GND
  DQ9_A  = M_L_CPU1_SA_DQ<9>
  VSS7  = GND
  DQS1_A_T  = M_L_CPU1_SA_DQS_DP<1>
  DQS1_A_C  = M_L_CPU1_SA_DQS_DN<1>
  VSS8  = GND
  DQ12_A  = M_L_CPU1_SA_DQ<12>
  VSS9  = GND
  DQ13_A  = M_L_CPU1_SA_DQ<13>
  VSS10  = GND
  DQ16_A  = M_L_CPU1_SA_DQ<16>
  VSS11  = GND
  DQ17_A  = M_L_CPU1_SA_DQ<17>
  VSS12  = GND
  DQS2_A_T  = M_L_CPU1_SA_DQS_DP<2>
  DQS2_A_C  = M_L_CPU1_SA_DQS_DN<2>
  VSS13  = GND
  DQ20_A  = M_L_CPU1_SA_DQ<20>
  VSS14  = GND
  DQ21_A  = M_L_CPU1_SA_DQ<21>
  VSS15  = GND
  DQ24_A  = M_L_CPU1_SA_DQ<24>
  VSS16  = GND
  DQ25_A  = M_L_CPU1_SA_DQ<25>
  VSS17  = GND
  DQS3_A_T  = M_L_CPU1_SA_DQS_DP<3>
  DQS3_A_C  = M_L_CPU1_SA_DQS_DN<3>
  VSS18  = GND
  DQ28_A  = M_L_CPU1_SA_DQ<28>
  VSS19  = GND
  DQ29_A  = M_L_CPU1_SA_DQ<29>
  VSS20  = GND
  CB0_A  = M_L_CPU1_SA_CB<0>
  VSS21  = GND
  CB1_A  = M_L_CPU1_SA_CB<1>
  VSS22  = GND
  DQS4_A_T  = M_L_CPU1_SA_DQS_DP<4>
  DQS4_A_C  = M_L_CPU1_SA_DQS_DN<4>
  VSS23  = GND
  CB4_A  = M_L_CPU1_SA_CB<4>
  VSS24  = GND
  CB5_A  = M_L_CPU1_SA_CB<5>
  VSS25  = GND
  ALERT_N  = M_L_CPU1_ALERT_N
  VSS26  = GND
  CS0_A_N  = M_L_CPU1_SA_CS_N<0>
  VSS27  = GND
  CA0_A  = M_L_CPU1_SA_CA<0>
  VSS28  = GND
  CA2_A  = M_L_CPU1_SA_CA<2>
  VSS29  = GND
  CA4_A  = M_L_CPU1_SA_CA<4>
  VSS30  = GND
  CA6_A  = M_L_CPU1_SA_CA<6>
  VSS31  = GND
  PAR_A  = M_L_CPU1_SA_PAR
  VSS32  = GND
  CA0_B  = M_L_CPU1_SB_CA<0>
  VSS33  = GND
  CA2_B  = M_L_CPU1_SB_CA<2>
  VSS34  = GND
  CA4_B  = M_L_CPU1_SB_CA<4>
  VSS35  = GND
  CA6_B  = M_L_CPU1_SB_CA<6>
  VSS36  = GND
  CS0_B_N  = M_L_CPU1_SB_CS_N<0>
  VSS37  = GND
  \lbd||rsp_a_n\  = M_L_CPU1_SA_RSP<0>
  \lbs||rsp_b_n\  = M_L_CPU1_SB_RSP<0>
  VSS38  = GND
  CB4_B  = M_L_CPU1_SB_CB<4>
  VSS39  = GND
  CB5_B  = M_L_CPU1_SB_CB<5>
  VSS40  = GND
  \dqs9_b_t||tdqs9_b_t||dbi4_b_n\  = M_L_CPU1_SB_DQS_DP<9>
  \dqs9_b_c||tdqs9_b_c\  = M_L_CPU1_SB_DQS_DN<9>
  VSS41  = GND
  CB0_B  = M_L_CPU1_SB_CB<0>
  VSS42  = GND
  CB1_B  = M_L_CPU1_SB_CB<1>
  VSS43  = GND
  DQ0_B  = M_L_CPU1_SB_DQ<0>
  VSS44  = GND
  DQ1_B  = M_L_CPU1_SB_DQ<1>
  VSS45  = GND
  DQS0_B_T  = M_L_CPU1_SB_DQS_DP<0>
  DQS0_B_C  = M_L_CPU1_SB_DQS_DN<0>
  VSS46  = GND
  DQ4_B  = M_L_CPU1_SB_DQ<4>
  VSS47  = GND
  DQ5_B  = M_L_CPU1_SB_DQ<5>
  VSS48  = GND
  DQ8_B  = M_L_CPU1_SB_DQ<8>
  VSS49  = GND
  DQ9_B  = M_L_CPU1_SB_DQ<9>
  VSS50  = GND
  DQS1_B_T  = M_L_CPU1_SB_DQS_DP<1>
  DQS1_B_C  = M_L_CPU1_SB_DQS_DN<1>
  VSS51  = GND
  DQ12_B  = M_L_CPU1_SB_DQ<12>
  VSS52  = GND
  DQ13_B  = M_L_CPU1_SB_DQ<13>
  VSS53  = GND
  DQ16_B  = M_L_CPU1_SB_DQ<16>
  VSS54  = GND
  DQ17_B  = M_L_CPU1_SB_DQ<17>
  VSS55  = GND
  DQS2_B_T  = M_L_CPU1_SB_DQS_DP<2>
  DQS2_B_C  = M_L_CPU1_SB_DQS_DN<2>
  VSS56  = GND
  DQ20_B  = M_L_CPU1_SB_DQ<20>
  VSS57  = GND
  DQ21_B  = M_L_CPU1_SB_DQ<21>
  VSS58  = GND
  DQ24_B  = M_L_CPU1_SB_DQ<24>
  VSS59  = GND
  DQ25_B  = M_L_CPU1_SB_DQ<25>
  VSS60  = GND
  DQS3_B_T  = M_L_CPU1_SB_DQS_DP<3>
  DQS3_B_C  = M_L_CPU1_SB_DQS_DN<3>
  VSS61  = GND
  DQ28_B  = M_L_CPU1_SB_DQ<28>
  VSS62  = GND
  DQ29_B  = M_L_CPU1_SB_DQ<29>
  VSS63  = GND
  RFU1  = NC
  VIN_BULK1  = P12V_MEM_CPU1
  VIN_BULK2  = P12V_MEM_CPU1
  \pwr_good||fail_n\  = PWRGD_CHL_CPU1_DIMM
  HAS  = PD_CHL_CPU1_DIMM_SAA
  RFU2  = NC
  RFU3  = NC
  VSS64  = GND
  DQ2_A  = M_L_CPU1_SA_DQ<2>
  VSS65  = GND
  DQ3_A  = M_L_CPU1_SA_DQ<3>
  VSS66  = GND
  \dqs5_a_c||tdqs5_a_c||dqs5_a_t||tdqs5_a_t\  = M_L_CPU1_SA_DQS_DN<5>
  \dqs5_a_t||tdqs5_a_t\  = M_L_CPU1_SA_DQS_DP<5>
  VSS67  = GND
  DQ6_A  = M_L_CPU1_SA_DQ<6>
  VSS68  = GND
  DQ7_A  = M_L_CPU1_SA_DQ<7>
  VSS69  = GND
  DQ10_A  = M_L_CPU1_SA_DQ<10>
  VSS70  = GND
  DQ11_A  = M_L_CPU1_SA_DQ<11>
  VSS71  = GND
  \dqs6_a_c||tdqs6_a_c||dqs6_a_t||tdqs6_a_t\  = M_L_CPU1_SA_DQS_DN<6>
  \dqs6_a_t||tdqs6_a_t\  = M_L_CPU1_SA_DQS_DP<6>
  VSS72  = GND
  DQ14_A  = M_L_CPU1_SA_DQ<14>
  VSS73  = GND
  DQ15_A  = M_L_CPU1_SA_DQ<15>
  VSS74  = GND
  DQ18_A  = M_L_CPU1_SA_DQ<18>
  VSS75  = GND
  DQ19_A  = M_L_CPU1_SA_DQ<19>
  VSS76  = GND
  \dqs7_a_c||tdqs7_a_c\  = M_L_CPU1_SA_DQS_DN<7>
  \dqs7_a_t||tdqs7_a_t\  = M_L_CPU1_SA_DQS_DP<7>
  VSS77  = GND
  DQ22_A  = M_L_CPU1_SA_DQ<22>
  VSS78  = GND
  DQ23_A  = M_L_CPU1_SA_DQ<23>
  VSS79  = GND
  DQ26_A  = M_L_CPU1_SA_DQ<26>
  VSS80  = GND
  DQ27_A  = M_L_CPU1_SA_DQ<27>
  VSS81  = GND
  \dqs8_a_c||tdqs8_a_c\  = M_L_CPU1_SA_DQS_DN<8>
  \dqs8_a_t||tdqs8_a_t\  = M_L_CPU1_SA_DQS_DP<8>
  VSS82  = GND
  DQ30_A  = M_L_CPU1_SA_DQ<30>
  VSS83  = GND
  DQ31_A  = M_L_CPU1_SA_DQ<31>
  VSS84  = GND
  CB2_A  = M_L_CPU1_SA_CB<2>
  VSS85  = GND
  CB3_A  = M_L_CPU1_SA_CB<3>
  VSS86  = GND
  \dqs9_a_c||tdqs9_a_c\  = M_L_CPU1_SA_DQS_DN<9>
  \dqs9_a_t||tdqs9_a_t\  = M_L_CPU1_SA_DQS_DP<9>
  VSS87  = GND
  CB6_A  = M_L_CPU1_SA_CB<6>
  VSS88  = GND
  CB7_A  = M_L_CPU1_SA_CB<7>
  VSS89  = GND
  RESET_N  = M_L_CPU1_RESET_N
  VSS90  = GND
  CS1_A_N  = M_L_CPU1_SA_CS_N<1>
  VSS91  = GND
  CA1_A  = M_L_CPU1_SA_CA<1>
  VSS92  = GND
  CA3_A  = M_L_CPU1_SA_CA<3>
  VSS93  = GND
  CA5_A  = M_L_CPU1_SA_CA<5>
  VSS94  = GND
  CK_T  = M_L_CPU1_CLK_DP<0>
  CK_C  = M_L_CPU1_CLK_DN<0>
  VSS95  = GND
  RFU4  = NC
  CA1_B  = M_L_CPU1_SB_CA<1>
  VSS96  = GND
  CA3_B  = M_L_CPU1_SB_CA<3>
  VSS97  = GND
  CA5_B  = M_L_CPU1_SB_CA<5>
  VSS98  = GND
  PAR_B  = M_L_CPU1_SB_PAR
  VSS99  = GND
  CS1_B_N  = M_L_CPU1_SB_CS_N<1>
  VSS100  = GND
  RFU5  = NC
  RFU6  = NC
  VSS101  = GND
  CB6_B  = M_L_CPU1_SB_CB<6>
  VSS102  = GND
  CB7_B  = M_L_CPU1_SB_CB<7>
  VSS103  = GND
  DQS4_B_C  = M_L_CPU1_SB_DQS_DN<4>
  DQS4_B_T  = M_L_CPU1_SB_DQS_DP<4>
  VSS104  = GND
  CB2_B  = M_L_CPU1_SB_CB<2>
  VSS105  = GND
  CB3_B  = M_L_CPU1_SB_CB<3>
  VSS106  = GND
  DQ2_B  = M_L_CPU1_SB_DQ<2>
  VSS107  = GND
  DQ3_B  = M_L_CPU1_SB_DQ<3>
  VSS108  = GND
  \dqs5_b_c||tdqs5_b_c\  = M_L_CPU1_SB_DQS_DN<5>
  \dqs5_b_t||tdqs5_b_t\  = M_L_CPU1_SB_DQS_DP<5>
  VSS109  = GND
  DQ6_B  = M_L_CPU1_SB_DQ<6>
  VSS110  = GND
  DQ7_B  = M_L_CPU1_SB_DQ<7>
  VSS111  = GND
  DQ10_B  = M_L_CPU1_SB_DQ<10>
  VSS112  = GND
  DQ11_B  = M_L_CPU1_SB_DQ<11>
  VSS113  = GND
  \dqs6_b_c||tdqs6_b_c\  = M_L_CPU1_SB_DQS_DN<6>
  \dqs6_b_t||tdqs6_b_t\  = M_L_CPU1_SB_DQS_DP<6>
  VSS114  = GND
  DQ14_B  = M_L_CPU1_SB_DQ<14>
  VSS115  = GND
  DQ15_B  = M_L_CPU1_SB_DQ<15>
  VSS116  = GND
  DQ18_B  = M_L_CPU1_SB_DQ<18>
  VSS117  = GND
  DQ19_B  = M_L_CPU1_SB_DQ<19>
  VSS118  = GND
  \dqs7_b_c||tdqs7_b_c\  = M_L_CPU1_SB_DQS_DN<7>
  \dqs7_b_t||tdqs7_b_t\  = M_L_CPU1_SB_DQS_DP<7>
  VSS119  = GND
  DQ22_B  = M_L_CPU1_SB_DQ<22>
  VSS120  = GND
  DQ23_B  = M_L_CPU1_SB_DQ<23>
  VSS121  = GND
  DQ26_B  = M_L_CPU1_SB_DQ<26>
  VSS122  = GND
  DQ27_B  = M_L_CPU1_SB_DQ<27>
  VSS123  = GND
  \dqs8_b_c||tdqs8_b_c\  = M_L_CPU1_SB_DQS_DN<8>
  \dqs8_b_t||tdqs8_b_t\  = M_L_CPU1_SB_DQS_DP<8>
  VSS124  = GND
  DQ30_B  = M_L_CPU1_SB_DQ<30>
  VSS125  = GND
  DQ31_B  = M_L_CPU1_SB_DQ<31>
  VSS126  = GND
  G1  = GND
  G2  = GND
  G3  = GND

(kicad_pcb
	(version 20260206)
	(generator "pcbnew")
	(generator_version "10.0")
	(general
		(thickness 1.6)
		(legacy_teardrops no)
	)
	(paper "A4")
	(title_block
		(title "04192023_DAF0TMB3IC0_F0TG_MB_C_brd_V02_OCP.brd")
		(comment 1 "Grand Teton / footprint 34 of 8354 (J37), pads 139-184 of 291")
	)
	(layers
		(0 "F.Cu" signal "TOP")
		(4 "In1.Cu" signal "GND")
		(6 "In2.Cu" signal "IN1")
		(8 "In3.Cu" signal "GND1")
		(10 "In4.Cu" signal "IN2")
		(12 "In5.Cu" signal "GND2")
		(14 "In6.Cu" signal "IN3")
		(16 "In7.Cu" signal "GND3")
		(18 "In8.Cu" signal "VCC")
		(20 "In9.Cu" signal "VCC1")
		(22 "In10.Cu" signal "GND4")
		(24 "In11.Cu" signal "IN4")
		(26 "In12.Cu" signal "GND5")
		(28 "In13.Cu" signal "IN5")
		(30 "In14.Cu" signal "GND6")
		(32 "In15.Cu" signal "IN6")
		(34 "In16.Cu" signal "GND7")
		(2 "B.Cu" signal "BOTTOM")
		(9 "F.Adhes" user "F.Adhesive")
		(11 "B.Adhes" user "B.Adhesive")
		(13 "F.Paste" user "Package Geometry/Pastemask Top")
		(15 "B.Paste" user "Package Geometry/Pastemask Bottom")
		(5 "F.SilkS" user "Ref Des/Silkscreen Top")
		(7 "B.SilkS" user "Ref Des/Silkscreen Bottom")
		(1 "F.Mask" user "Board Geometry/Soldermask Top")
		(3 "B.Mask" user "Board Geometry/Soldermask Bottom")
		(17 "Dwgs.User" user "User.Drawings")
		(19 "Cmts.User" user "User.Comments")
		(21 "Eco1.User" user "User.Eco1")
		(23 "Eco2.User" user "User.Eco2")
		(25 "Edge.Cuts" user "Board Geometry/Outline")
		(27 "Margin" user)
		(31 "F.CrtYd" user "Package Geometry/Place Bound Top")
		(29 "B.CrtYd" user "Package Geometry/Place Bound Bottom")
		(35 "F.Fab" user "Ref Des/Assembly Top")
		(33 "B.Fab" user "Ref Des/Assembly Bottom")
	)
	(footprint ""
		(layer "F.Cu")
		(at 204.197966 -255.560322 180)
		(property "Reference" "J37"
			(at 2.8702 -81.730088 0)
			(unlocked yes)
			(layer "F.SilkS")
			(effects
				(font
					(size 0.7874 0.5842)
					(thickness 0.1524)
				)
			)
		)
		(property "Value" ""
			(at 0 0 180)
			(layer "F.Fab")
			(effects
				(font
					(size 1.27 1.27)
				)
			)
		)
		(duplicate_pad_numbers_are_jumpers no)
		(pad "139" smd rect
			(at -2.050034 59.075066 90)
			(size 0.519938 1.4986)
			(layers "F.Cu" "F.Mask" "F.Paste")
			(net "GND")
		)
		(pad "140" smd rect
			(at -2.050034 59.92495 90)
			(size 0.519938 1.4986)
			(layers "F.Cu" "F.Mask" "F.Paste")
			(net "M_L_CPU1_SB_DQ<28>")
		)
		(pad "141" smd rect
			(at -2.050034 60.775088 90)
			(size 0.519938 1.4986)
			(layers "F.Cu" "F.Mask" "F.Paste")
			(net "GND")
		)
		(pad "142" smd rect
			(at -2.050034 61.624972 90)
			(size 0.519938 1.4986)
			(layers "F.Cu" "F.Mask" "F.Paste")
			(net "M_L_CPU1_SB_DQ<29>")
		)
		(pad "143" smd rect
			(at -2.050034 62.47511 90)
			(size 0.519938 1.4986)
			(layers "F.Cu" "F.Mask" "F.Paste")
			(net "GND")
		)
		(pad "144" smd rect
			(at -2.050034 63.324994 90)
			(size 0.519938 1.4986)
			(layers "F.Cu" "F.Mask" "F.Paste")
			(net "Net_2411")
		)
		(pad "145" smd rect
			(at 2.050034 -63.324994 90)
			(size 0.519938 1.4986)
			(layers "F.Cu" "F.Mask" "F.Paste")
			(net "P12V_MEM_CPU1")
		)
		(pad "146" smd rect
			(at 2.050034 -62.47511 90)
			(size 0.519938 1.4986)
			(layers "F.Cu" "F.Mask" "F.Paste")
			(net "P12V_MEM_CPU1")
		)
		(pad "147" smd rect
			(at 2.050034 -61.624972 90)
			(size 0.519938 1.4986)
			(layers "F.Cu" "F.Mask" "F.Paste")
			(net "PWRGD_CHL_CPU1_DIMM")
		)
		(pad "148" smd rect
			(at 2.050034 -60.775088 90)
			(size 0.519938 1.4986)
			(layers "F.Cu" "F.Mask" "F.Paste")
			(net "PD_CHL_CPU1_DIMM_SAA")
		)
		(pad "149" smd rect
			(at 2.050034 -59.92495 90)
			(size 0.519938 1.4986)
			(layers "F.Cu" "F.Mask" "F.Paste")
			(net "Net_2412")
		)
		(pad "150" smd rect
			(at 2.050034 -59.075066 90)
			(size 0.519938 1.4986)
			(layers "F.Cu" "F.Mask" "F.Paste")
			(net "Net_2413")
		)
		(pad "151" smd rect
			(at 2.050034 -58.224928 90)
			(size 0.519938 1.4986)
			(layers "F.Cu" "F.Mask" "F.Paste")
			(net "GND")
		)
		(pad "152" smd rect
			(at 2.050034 -57.375044 90)
			(size 0.519938 1.4986)
			(layers "F.Cu" "F.Mask" "F.Paste")
			(net "M_L_CPU1_SA_DQ<2>")
		)
		(pad "153" smd rect
			(at 2.050034 -56.524906 90)
			(size 0.519938 1.4986)
			(layers "F.Cu" "F.Mask" "F.Paste")
			(net "GND")
		)
		(pad "154" smd rect
			(at 2.050034 -55.675022 90)
			(size 0.519938 1.4986)
			(layers "F.Cu" "F.Mask" "F.Paste")
			(net "M_L_CPU1_SA_DQ<3>")
		)
		(pad "155" smd rect
			(at 2.050034 -54.824884 90)
			(size 0.519938 1.4986)
			(layers "F.Cu" "F.Mask" "F.Paste")
			(net "GND")
		)
		(pad "156" smd rect
			(at 2.050034 -53.975 90)
			(size 0.519938 1.4986)
			(layers "F.Cu" "F.Mask" "F.Paste")
			(net "M_L_CPU1_SA_DQS_DN<5>")
		)
		(pad "157" smd rect
			(at 2.050034 -53.125116 90)
			(size 0.519938 1.4986)
			(layers "F.Cu" "F.Mask" "F.Paste")
			(net "M_L_CPU1_SA_DQS_DP<5>")
		)
		(pad "158" smd rect
			(at 2.050034 -52.274978 90)
			(size 0.519938 1.4986)
			(layers "F.Cu" "F.Mask" "F.Paste")
			(net "GND")
		)
		(pad "159" smd rect
			(at 2.050034 -51.425094 90)
			(size 0.519938 1.4986)
			(layers "F.Cu" "F.Mask" "F.Paste")
			(net "M_L_CPU1_SA_DQ<6>")
		)
		(pad "160" smd rect
			(at 2.050034 -50.574956 90)
			(size 0.519938 1.4986)
			(layers "F.Cu" "F.Mask" "F.Paste")
			(net "GND")
		)
		(pad "161" smd rect
			(at 2.050034 -49.725072 90)
			(size 0.519938 1.4986)
			(layers "F.Cu" "F.Mask" "F.Paste")
			(net "M_L_CPU1_SA_DQ<7>")
		)
		(pad "162" smd rect
			(at 2.050034 -48.874934 90)
			(size 0.519938 1.4986)
			(layers "F.Cu" "F.Mask" "F.Paste")
			(net "GND")
		)
		(pad "163" smd rect
			(at 2.050034 -48.02505 90)
			(size 0.519938 1.4986)
			(layers "F.Cu" "F.Mask" "F.Paste")
			(net "M_L_CPU1_SA_DQ<10>")
		)
		(pad "164" smd rect
			(at 2.050034 -47.174912 90)
			(size 0.519938 1.4986)
			(layers "F.Cu" "F.Mask" "F.Paste")
			(net "GND")
		)
		(pad "165" smd rect
			(at 2.050034 -46.325028 90)
			(size 0.519938 1.4986)
			(layers "F.Cu" "F.Mask" "F.Paste")
			(net "M_L_CPU1_SA_DQ<11>")
		)
		(pad "166" smd rect
			(at 2.050034 -45.47489 90)
			(size 0.519938 1.4986)
			(layers "F.Cu" "F.Mask" "F.Paste")
			(net "GND")
		)
		(pad "167" smd rect
			(at 2.050034 -44.625006 90)
			(size 0.519938 1.4986)
			(layers "F.Cu" "F.Mask" "F.Paste")
			(net "M_L_CPU1_SA_DQS_DN<6>")
		)
		(pad "168" smd rect
			(at 2.050034 -43.775122 90)
			(size 0.519938 1.4986)
			(layers "F.Cu" "F.Mask" "F.Paste")
			(net "M_L_CPU1_SA_DQS_DP<6>")
		)
		(pad "169" smd rect
			(at 2.050034 -42.924984 90)
			(size 0.519938 1.4986)
			(layers "F.Cu" "F.Mask" "F.Paste")
			(net "GND")
		)
		(pad "170" smd rect
			(at 2.050034 -42.0751 90)
			(size 0.519938 1.4986)
			(layers "F.Cu" "F.Mask" "F.Paste")
			(net "M_L_CPU1_SA_DQ<14>")
		)
		(pad "171" smd rect
			(at 2.050034 -41.224962 90)
			(size 0.519938 1.4986)
			(layers "F.Cu" "F.Mask" "F.Paste")
			(net "GND")
		)
		(pad "172" smd rect
			(at 2.050034 -40.375078 90)
			(size 0.519938 1.4986)
			(layers "F.Cu" "F.Mask" "F.Paste")
			(net "M_L_CPU1_SA_DQ<15>")
		)
		(pad "173" smd rect
			(at 2.050034 -39.52494 90)
			(size 0.519938 1.4986)
			(layers "F.Cu" "F.Mask" "F.Paste")
			(net "GND")
		)
		(pad "174" smd rect
			(at 2.050034 -38.675056 90)
			(size 0.519938 1.4986)
			(layers "F.Cu" "F.Mask" "F.Paste")
			(net "M_L_CPU1_SA_DQ<18>")
		)
		(pad "175" smd rect
			(at 2.050034 -37.824918 90)
			(size 0.519938 1.4986)
			(layers "F.Cu" "F.Mask" "F.Paste")
			(net "GND")
		)
		(pad "176" smd rect
			(at 2.050034 -36.975034 90)
			(size 0.519938 1.4986)
			(layers "F.Cu" "F.Mask" "F.Paste")
			(net "M_L_CPU1_SA_DQ<19>")
		)
		(pad "177" smd rect
			(at 2.050034 -36.124896 90)
			(size 0.519938 1.4986)
			(layers "F.Cu" "F.Mask" "F.Paste")
			(net "GND")
		)
		(pad "178" smd rect
			(at 2.050034 -35.275012 90)
			(size 0.519938 1.4986)
			(layers "F.Cu" "F.Mask" "F.Paste")
			(net "M_L_CPU1_SA_DQS_DN<7>")
		)
		(pad "179" smd rect
			(at 2.050034 -34.425128 90)
			(size 0.519938 1.4986)
			(layers "F.Cu" "F.Mask" "F.Paste")
			(net "M_L_CPU1_SA_DQS_DP<7>")
		)
		(pad "180" smd rect
			(at 2.050034 -33.57499 90)
			(size 0.519938 1.4986)
			(layers "F.Cu" "F.Mask" "F.Paste")
			(net "GND")
		)
		(pad "181" smd rect
			(at 2.050034 -32.725106 90)
			(size 0.519938 1.4986)
			(layers "F.Cu" "F.Mask" "F.Paste")
			(net "M_L_CPU1_SA_DQ<22>")
		)
		(pad "182" smd rect
			(at 2.050034 -31.874968 90)
			(size 0.519938 1.4986)
			(layers "F.Cu" "F.Mask" "F.Paste")
			(net "GND")
		)
		(pad "183" smd rect
			(at 2.050034 -31.025084 90)
			(size 0.519938 1.4986)
			(layers "F.Cu" "F.Mask" "F.Paste")
			(net "M_L_CPU1_SA_DQ<23>")
		)
		(pad "184" smd rect
			(at 2.050034 -30.174946 90)
			(size 0.519938 1.4986)
			(layers "F.Cu" "F.Mask" "F.Paste")
			(net "GND")
		)
	)
)
